# T6G (Grand Teton) — schematic netlist excerpt (pin names and nets, part order shuffled) for the footprints in the layout excerpt that follows; sources: Cadence DE-HDL packaged netlist, KiCad conversion of 04192023_DAF0TMB3IC0_F0TG_MB_C_brd_V02_OCP.brd

C6540  Q_CAP_DIFFBUS  DIFF BUS_0.22UF 6.3V 20% X6S  pkg C0201  page 286 : \1\ = P5E_CPU0_P1_TX_BUF_C_DN<3> ; \2\ = P5E_CPU0_P1_TX_BUF_DN<3>
C6076  Q_CAP  0.01UF 50V 10% X7R  pkg C0402  page 177 : A = P1V2_AUX ; B = GND
C2437  Q_CAP  22UF 4V 20% X6S  pkg C0402  page 74 : A = PVDDCR_SOC_P1 ; B = GND

(kicad_pcb
	(version 20260206)
	(generator "pcbnew")
	(generator_version "10.0")
	(general
		(thickness 1.6)
		(legacy_teardrops no)
	)
	(paper "A4")
	(title_block
		(title "04192023_DAF0TMB3IC0_F0TG_MB_C_brd_V02_OCP.brd")
		(comment 1 "Grand Teton / footprints 6647-6649 of 8354")
	)
	(layers
		(0 "F.Cu" signal "TOP")
		(4 "In1.Cu" signal "GND")
		(6 "In2.Cu" signal "IN1")
		(8 "In3.Cu" signal "GND1")
		(10 "In4.Cu" signal "IN2")
		(12 "In5.Cu" signal "GND2")
		(14 "In6.Cu" signal "IN3")
		(16 "In7.Cu" signal "GND3")
		(18 "In8.Cu" signal "VCC")
		(20 "In9.Cu" signal "VCC1")
		(22 "In10.Cu" signal "GND4")
		(24 "In11.Cu" signal "IN4")
		(26 "In12.Cu" signal "GND5")
		(28 "In13.Cu" signal "IN5")
		(30 "In14.Cu" signal "GND6")
		(32 "In15.Cu" signal "IN6")
		(34 "In16.Cu" signal "GND7")
		(2 "B.Cu" signal "BOTTOM")
		(9 "F.Adhes" user "F.Adhesive")
		(11 "B.Adhes" user "B.Adhesive")
		(13 "F.Paste" user "Package Geometry/Pastemask Top")
		(15 "B.Paste" user "Package Geometry/Pastemask Bottom")
		(5 "F.SilkS" user "Ref Des/Silkscreen Top")
		(7 "B.SilkS" user "Ref Des/Silkscreen Bottom")
		(1 "F.Mask" user "Board Geometry/Soldermask Top")
		(3 "B.Mask" user "Board Geometry/Soldermask Bottom")
		(17 "Dwgs.User" user "User.Drawings")
		(19 "Cmts.User" user "User.Comments")
		(21 "Eco1.User" user "User.Eco1")
		(23 "Eco2.User" user "User.Eco2")
		(25 "Edge.Cuts" user "Board Geometry/Outline")
		(27 "Margin" user)
		(31 "F.CrtYd" user "Package Geometry/Place Bound Top")
		(29 "B.CrtYd" user "Package Geometry/Place Bound Bottom")
		(35 "F.Fab" user "Ref Des/Assembly Top")
		(33 "B.Fab" user "Ref Des/Assembly Bottom")
	)
	(footprint ""
		(layer "B.Cu")
		(at 314.489846 -416.899344 90)
		(property "Reference" "C6540"
			(at 0 0 90)
			(layer "B.SilkS")
			(hide yes)
			(effects
				(font
					(size 1.27 1.27)
				)
				(justify mirror)
			)
		)
		(property "Value" ""
			(at 0 0 90)
			(layer "B.Fab")
			(effects
				(font
					(size 1.27 1.27)
				)
				(justify mirror)
			)
		)
		(duplicate_pad_numbers_are_jumpers no)
		(fp_line
			(start 0.299974 -0.150114)
			(end -0.299974 -0.150114)
			(stroke
				(width 0.1)
				(type default)
			)
			(layer "B.Fab")
		)
		(fp_line
			(start -0.299974 -0.150114)
			(end -0.299974 0.150114)
			(stroke
				(width 0.1)
				(type default)
			)
			(layer "B.Fab")
		)
		(fp_line
			(start 0.299974 0.150114)
			(end 0.299974 -0.150114)
			(stroke
				(width 0.1)
				(type default)
			)
			(layer "B.Fab")
		)
		(fp_line
			(start -0.299974 0.150114)
			(end 0.299974 0.150114)
			(stroke
				(width 0.1)
				(type default)
			)
			(layer "B.Fab")
		)
		(pad "1" smd rect
			(at 0.2667 0 270)
			(size 0.3048 0.381)
			(layers "B.Cu" "B.Mask" "B.Paste")
			(net "P5E_CPU0_P1_TX_BUF_C_DN<3>")
		)
		(pad "2" smd rect
			(at -0.2667 0 270)
			(size 0.3048 0.381)
			(layers "B.Cu" "B.Mask" "B.Paste")
			(net "P5E_CPU0_P1_TX_BUF_DN<3>")
		)
	)
	(footprint ""
		(layer "B.Cu")
		(at 117.895624 -261.255256)
		(property "Reference" "C2437"
			(at 0 0 0)
			(layer "B.SilkS")
			(hide yes)
			(effects
				(font
					(size 1.27 1.27)
				)
				(justify mirror)
			)
		)
		(property "Value" ""
			(at 0 0 0)
			(layer "B.Fab")
			(effects
				(font
					(size 1.27 1.27)
				)
				(justify mirror)
			)
		)
		(duplicate_pad_numbers_are_jumpers no)
		(fp_line
			(start -0.7874 -0.4064)
			(end -0.7874 0.4064)
			(stroke
				(width 0.1524)
				(type default)
			)
			(layer "B.SilkS")
		)
		(fp_line
			(start -0.7874 0.4064)
			(end 0.7874 0.4064)
			(stroke
				(width 0.1524)
				(type default)
			)
			(layer "B.SilkS")
		)
		(fp_line
			(start 0.7874 -0.4064)
			(end -0.7874 -0.4064)
			(stroke
				(width 0.1524)
				(type default)
			)
			(layer "B.SilkS")
		)
		(fp_line
			(start 0.7874 0.4064)
			(end 0.7874 -0.4064)
			(stroke
				(width 0.1524)
				(type default)
			)
			(layer "B.SilkS")
		)
		(fp_line
			(start -0.67945 -0.3048)
			(end -0.67945 0.3048)
			(stroke
				(width 0.1)
				(type default)
			)
			(layer "B.Fab")
		)
		(fp_line
			(start -0.67945 0.3048)
			(end -0.120396 0.3048)
			(stroke
				(width 0.1)
				(type default)
			)
			(layer "B.Fab")
		)
		(fp_line
			(start -0.12065 -0.3048)
			(end -0.67945 -0.3048)
			(stroke
				(width 0.1)
				(type default)
			)
			(layer "B.Fab")
		)
		(fp_line
			(start -0.12065 -0.2794)
			(end -0.12065 -0.3048)
			(stroke
				(width 0.1)
				(type default)
			)
			(layer "B.Fab")
		)
		(fp_line
			(start -0.120396 0.2794)
			(end 0.12065 0.2794)
			(stroke
				(width 0.1)
				(type default)
			)
			(layer "B.Fab")
		)
		(fp_line
			(start -0.120396 0.3048)
			(end -0.120396 0.2794)
			(stroke
				(width 0.1)
				(type default)
			)
			(layer "B.Fab")
		)
		(fp_line
			(start 0.12065 -0.305054)
			(end 0.12065 -0.2794)
			(stroke
				(width 0.1)
				(type default)
			)
			(layer "B.Fab")
		)
		(fp_line
			(start 0.12065 -0.2794)
			(end -0.12065 -0.2794)
			(stroke
				(width 0.1)
				(type default)
			)
			(layer "B.Fab")
		)
		(fp_line
			(start 0.12065 0.2794)
			(end 0.12065 0.3048)
			(stroke
				(width 0.1)
				(type default)
			)
			(layer "B.Fab")
		)
		(fp_line
			(start 0.12065 0.3048)
			(end 0.67945 0.3048)
			(stroke
				(width 0.1)
				(type default)
			)
			(layer "B.Fab")
		)
		(fp_line
			(start 0.67945 -0.305054)
			(end 0.12065 -0.305054)
			(stroke
				(width 0.1)
				(type default)
			)
			(layer "B.Fab")
		)
		(fp_line
			(start 0.67945 0.3048)
			(end 0.67945 -0.305054)
			(stroke
				(width 0.1)
				(type default)
			)
			(layer "B.Fab")
		)
		(pad "1" smd circle
			(at 0.40005 0 180)
			(size 0 0)
			(layers "B.Cu" "B.Mask" "B.Paste")
			(net "PVDDCR_SOC_P1")
		)
		(pad "2" smd circle
			(at -0.40005 0 180)
			(size 0 0)
			(layers "B.Cu" "B.Mask" "B.Paste")
			(net "GND")
		)
	)
	(footprint ""
		(layer "B.Cu")
		(at 127.908304 -32.867092 -90)
		(property "Reference" "C6076"
			(at 0 0 90)
			(layer "B.SilkS")
			(hide yes)
			(effects
				(font
					(size 1.27 1.27)
				)
				(justify mirror)
			)
		)
		(property "Value" ""
			(at 0 0 90)
			(layer "B.Fab")
			(effects
				(font
					(size 1.27 1.27)
				)
				(justify mirror)
			)
		)
		(duplicate_pad_numbers_are_jumpers no)
		(fp_line
			(start -0.7874 0.4064)
			(end 0.7874 0.4064)
			(stroke
				(width 0.1524)
				(type default)
			)
			(layer "B.SilkS")
		)
		(fp_line
			(start 0.7874 0.4064)
			(end 0.7874 -0.4064)
			(stroke
				(width 0.1524)
				(type default)
			)
			(layer "B.SilkS")
		)
		(fp_line
			(start -0.7874 -0.4064)
			(end -0.7874 0.4064)
			(stroke
				(width 0.1524)
				(type default)
			)
			(layer "B.SilkS")
		)
		(fp_line
			(start 0.7874 -0.4064)
			(end -0.7874 -0.4064)
			(stroke
				(width 0.1524)
				(type default)
			)
			(layer "B.SilkS")
		)
		(fp_line
			(start -0.67945 0.3048)
			(end -0.120396 0.3048)
			(stroke
				(width 0.1)
				(type default)
			)
			(layer "B.Fab")
		)
		(fp_line
			(start -0.120396 0.3048)
			(end -0.120396 0.2794)
			(stroke
				(width 0.1)
				(type default)
			)
			(layer "B.Fab")
		)
		(fp_line
			(start 0.12065 0.3048)
			(end 0.67945 0.3048)
			(stroke
				(width 0.1)
				(type default)
			)
			(layer "B.Fab")
		)
		(fp_line
			(start 0.67945 0.3048)
			(end 0.67945 -0.305054)
			(stroke
				(width 0.1)
				(type default)
			)
			(layer "B.Fab")
		)
		(fp_line
			(start -0.120396 0.2794)
			(end 0.12065 0.2794)
			(stroke
				(width 0.1)
				(type default)
			)
			(layer "B.Fab")
		)
		(fp_line
			(start 0.12065 0.2794)
			(end 0.12065 0.3048)
			(stroke
				(width 0.1)
				(type default)
			)
			(layer "B.Fab")
		)
		(fp_line
			(start -0.12065 -0.2794)
			(end -0.12065 -0.3048)
			(stroke
				(width 0.1)
				(type default)
			)
			(layer "B.Fab")
		)
		(fp_line
			(start 0.12065 -0.2794)
			(end -0.12065 -0.2794)
			(stroke
				(width 0.1)
				(type default)
			)
			(layer "B.Fab")
		)
		(fp_line
			(start -0.67945 -0.3048)
			(end -0.67945 0.3048)
			(stroke
				(width 0.1)
				(type default)
			)
			(layer "B.Fab")
		)
		(fp_line
			(start -0.12065 -0.3048)
			(end -0.67945 -0.3048)
			(stroke
				(width 0.1)
				(type default)
			)
			(layer "B.Fab")
		)
		(fp_line
			(start 0.12065 -0.305054)
			(end 0.12065 -0.2794)
			(stroke
				(width 0.1)
				(type default)
			)
			(layer "B.Fab")
		)
		(fp_line
			(start 0.67945 -0.305054)
			(end 0.12065 -0.305054)
			(stroke
				(width 0.1)
				(type default)
			)
			(layer "B.Fab")
		)
		(pad "1" smd circle
			(at 0.40005 0 90)
			(size 0 0)
			(layers "B.Cu" "B.Mask" "B.Paste")
			(net "P1V2_AUX")
		)
		(pad "2" smd circle
			(at -0.40005 0 90)
			(size 0 0)
			(layers "B.Cu" "B.Mask" "B.Paste")
			(net "GND")
		)
	)
)
